(kicad_pcb
	(version 20260206)
	(generator "pcbnew")
	(generator_version "10.0")
	(general
		(thickness 1.6)
		(legacy_teardrops no)
	)
	(paper "A4")
	(title_block
		(title "pdpb — Lightning_PDPB_BRD.brd")
		(comment 1 "Lightning (Wiwynn / Facebook NVMe JBOF) / footprints 910-916 of 1140")
	)
	(layers
		(0 "F.Cu" signal "TOP")
		(4 "In1.Cu" signal "L2GND")
		(6 "In2.Cu" signal "L3")
		(8 "In3.Cu" signal "L4VCC")
		(10 "In4.Cu" signal "L5VCC")
		(12 "In5.Cu" signal "L6")
		(14 "In6.Cu" signal "L7GND")
		(2 "B.Cu" signal "BOTTOM")
		(9 "F.Adhes" user "F.Adhesive")
		(11 "B.Adhes" user "B.Adhesive")
		(13 "F.Paste" user "Package Geometry/Pastemask Top")
		(15 "B.Paste" user "Package Geometry/Pastemask Bottom")
		(5 "F.SilkS" user "Ref Des/Silkscreen Top")
		(7 "B.SilkS" user "Ref Des/Silkscreen Bottom")
		(1 "F.Mask" user "Board Geometry/Soldermask Top")
		(3 "B.Mask" user "Board Geometry/Soldermask Bottom")
		(17 "Dwgs.User" user "User.Drawings")
		(19 "Cmts.User" user "User.Comments")
		(21 "Eco1.User" user "User.Eco1")
		(23 "Eco2.User" user "User.Eco2")
		(25 "Edge.Cuts" user "Board Geometry/Outline")
		(27 "Margin" user)
		(31 "F.CrtYd" user "Package Geometry/Place Bound Top")
		(29 "B.CrtYd" user "Package Geometry/Place Bound Bottom")
		(35 "F.Fab" user "Ref Des/Assembly Top")
		(33 "B.Fab" user "Ref Des/Assembly Bottom")
	)
	(footprint ""
		(layer "F.Cu")
		(at 36.6776 -109.8804 180)
		(property "Reference" "C395"
			(at 0 0 180)
			(layer "F.SilkS")
			(hide yes)
			(effects
				(font
					(size 1.27 1.27)
				)
			)
		)
		(property "Value" "SCD1U25V2KX-2-GP"
			(at 1.1811 -2.7051 180)
			(unlocked yes)
			(layer "F.Fab")
			(hide yes)
			(effects
				(font
					(size 1.016 1.016)
					(thickness 0.1524)
				)
			)
		)
		(property "Device Type" "C402H22"
			(at 1.1811 -4.2291 180)
			(unlocked yes)
			(layer "F.Fab")
			(hide yes)
			(effects
				(font
					(size 1.016 1.016)
					(thickness 0.1524)
				)
			)
		)
		(duplicate_pad_numbers_are_jumpers no)
		(fp_rect
			(start -0.4318 0.9525)
			(end 0.4318 -0.9525)
			(stroke
				(width 0)
				(type default)
			)
			(fill no)
			(layer "F.CrtYd")
		)
		(fp_rect
			(start -0.4318 0.9525)
			(end 0.4318 -0.9525)
			(stroke
				(width 0)
				(type default)
			)
			(fill no)
			(layer "F.Fab")
		)
		(pad "1" smd custom
			(at 0 -0.4445 180)
			(size 0.1524 0.1524)
			(layers "F.Cu" "F.Mask" "F.Paste")
			(net "P12V")
			(options
				(clearance outline)
				(anchor circle)
			)
			(primitives
				(gr_poly
					(pts
						(arc
							(start 0.3048 -0.2032)
							(mid 0.275042 -0.275042)
							(end 0.2032 -0.3048)
						)
						(arc
							(start -0.2032 -0.3048)
							(mid -0.275042 -0.275042)
							(end -0.3048 -0.2032)
						)
						(arc
							(start -0.3048 0.2032)
							(mid -0.275042 0.275042)
							(end -0.2032 0.3048)
						)
						(arc
							(start 0.2032 0.3048)
							(mid 0.275042 0.275042)
							(end 0.3048 0.2032)
						)
					)
					(width 0)
					(fill yes)
				)
			)
		)
		(pad "2" smd custom
			(at 0 0.4445 180)
			(size 0.1524 0.1524)
			(layers "F.Cu" "F.Mask" "F.Paste")
			(net "SW_SSD13_N")
			(options
				(clearance outline)
				(anchor circle)
			)
			(primitives
				(gr_poly
					(pts
						(arc
							(start 0.3048 -0.2032)
							(mid 0.275042 -0.275042)
							(end 0.2032 -0.3048)
						)
						(arc
							(start -0.2032 -0.3048)
							(mid -0.275042 -0.275042)
							(end -0.3048 -0.2032)
						)
						(arc
							(start -0.3048 0.2032)
							(mid -0.275042 0.275042)
							(end -0.2032 0.3048)
						)
						(arc
							(start 0.2032 0.3048)
							(mid 0.275042 0.275042)
							(end 0.3048 0.2032)
						)
					)
					(width 0)
					(fill yes)
				)
			)
		)
	)
	(footprint ""
		(layer "F.Cu")
		(at 29.845 -320.167 90)
		(property "Reference" "R412"
			(at 0 0 90)
			(layer "F.SilkS")
			(hide yes)
			(effects
				(font
					(size 1.27 1.27)
				)
			)
		)
		(property "Value" "0R2J-2-GP"
			(at 0.064008 -3.993896 90)
			(unlocked yes)
			(layer "F.Fab")
			(hide yes)
			(effects
				(font
					(size 1.016 1.016)
					(thickness 0.1524)
				)
			)
		)
		(property "Device Type" "R402H16"
			(at 0.064008 -5.517896 90)
			(unlocked yes)
			(layer "F.Fab")
			(hide yes)
			(effects
				(font
					(size 1.016 1.016)
					(thickness 0.1524)
				)
			)
		)
		(duplicate_pad_numbers_are_jumpers no)
		(fp_line
			(start 0.508 -0.9398)
			(end -0.508 -0.9398)
			(stroke
				(width 0.1524)
				(type default)
			)
			(layer "F.SilkS")
		)
		(fp_line
			(start -0.508 -0.9398)
			(end -0.508 0.9398)
			(stroke
				(width 0.1524)
				(type default)
			)
			(layer "F.SilkS")
		)
		(fp_rect
			(start -0.508 0.9398)
			(end 0.508 -0.9398)
			(stroke
				(width 0)
				(type default)
			)
			(fill no)
			(layer "F.CrtYd")
		)
		(fp_rect
			(start -0.508 0.9398)
			(end 0.508 -0.9398)
			(stroke
				(width 0)
				(type default)
			)
			(fill no)
			(layer "F.Fab")
		)
		(pad "1" smd custom
			(at 0 -0.4445 90)
			(size 0.1397 0.1397)
			(layers "F.Cu" "F.Mask" "F.Paste")
			(net "SDA_DR11_R")
			(options
				(clearance outline)
				(anchor circle)
			)
			(primitives
				(gr_poly
					(pts
						(arc
							(start -0.1778 -0.2794)
							(mid -0.249642 -0.249642)
							(end -0.2794 -0.1778)
						)
						(arc
							(start -0.2794 0.1778)
							(mid -0.249642 0.249642)
							(end -0.1778 0.2794)
						)
						(arc
							(start 0.1778 0.2794)
							(mid 0.249642 0.249642)
							(end 0.2794 0.1778)
						)
						(arc
							(start 0.2794 -0.1778)
							(mid 0.249642 -0.249642)
							(end 0.1778 -0.2794)
						)
					)
					(width 0)
					(fill yes)
				)
			)
		)
		(pad "2" smd custom
			(at 0 0.4445 90)
			(size 0.1397 0.1397)
			(layers "F.Cu" "F.Mask" "F.Paste")
			(net "SDA_DR11")
			(options
				(clearance outline)
				(anchor circle)
			)
			(primitives
				(gr_poly
					(pts
						(arc
							(start -0.1778 -0.2794)
							(mid -0.249642 -0.249642)
							(end -0.2794 -0.1778)
						)
						(arc
							(start -0.2794 0.1778)
							(mid -0.249642 0.249642)
							(end -0.1778 0.2794)
						)
						(arc
							(start 0.1778 0.2794)
							(mid 0.249642 0.249642)
							(end 0.2794 0.1778)
						)
						(arc
							(start 0.2794 -0.1778)
							(mid 0.249642 -0.249642)
							(end 0.1778 -0.2794)
						)
					)
					(width 0)
					(fill yes)
				)
			)
		)
	)
	(footprint ""
		(layer "F.Cu")
		(at 28.67025 -402.53285 -90)
		(property "Reference" "Q56"
			(at 0 0 270)
			(layer "F.SilkS")
			(hide yes)
			(effects
				(font
					(size 1.27 1.27)
				)
			)
		)
		(property "Value" "2N7002A-7-GP"
			(at 0.127 -8.9662 270)
			(unlocked yes)
			(layer "F.Fab")
			(hide yes)
			(effects
				(font
					(size 1.016 1.016)
					(thickness 0.1524)
				)
			)
		)
		(property "Device Type" "SOT23DGS2D4H48"
			(at 0.127 -10.4902 270)
			(unlocked yes)
			(layer "F.Fab")
			(hide yes)
			(effects
				(font
					(size 1.016 1.016)
					(thickness 0.1524)
				)
			)
		)
		(duplicate_pad_numbers_are_jumpers no)
		(fp_line
			(start -1.651 1.778)
			(end 1.651 1.778)
			(stroke
				(width 0.1524)
				(type default)
			)
			(layer "F.SilkS")
		)
		(fp_line
			(start 1.651 1.778)
			(end 1.651 -1.778)
			(stroke
				(width 0.1524)
				(type default)
			)
			(layer "F.SilkS")
		)
		(fp_line
			(start -1.651 -1.778)
			(end -1.651 1.778)
			(stroke
				(width 0.1524)
				(type default)
			)
			(layer "F.SilkS")
		)
		(fp_line
			(start 1.651 -1.778)
			(end -1.651 -1.778)
			(stroke
				(width 0.1524)
				(type default)
			)
			(layer "F.SilkS")
		)
		(fp_poly
			(pts
				(xy -1.778 1.8796) (xy -1.778 -1.8796) (xy 1.778 -1.8796) (xy 1.778 1.8796)
			)
			(stroke
				(width 0)
				(type default)
			)
			(fill no)
			(layer "F.CrtYd")
		)
		(fp_poly
			(pts
				(xy -1.778 1.8796) (xy -1.778 -1.8796) (xy 1.778 -1.8796) (xy 1.778 1.8796)
			)
			(stroke
				(width 0)
				(type default)
			)
			(fill no)
			(layer "F.Fab")
		)
		(pad "D" smd custom
			(at 0 -0.9525 270)
			(size 0.1905 0.1905)
			(layers "F.Cu" "F.Mask" "F.Paste")
			(net "P12V_MOST6_GATE_D")
			(options
				(clearance outline)
				(anchor circle)
			)
			(primitives
				(gr_poly
					(pts
						(arc
							(start -0.1778 0.5715)
							(mid -0.321484 0.511984)
							(end -0.381 0.3683)
						)
						(arc
							(start -0.381 -0.3683)
							(mid -0.321484 -0.511984)
							(end -0.1778 -0.5715)
						)
						(arc
							(start 0.1778 -0.5715)
							(mid 0.321484 -0.511984)
							(end 0.381 -0.3683)
						)
						(arc
							(start 0.381 0.3683)
							(mid 0.321484 0.511984)
							(end 0.1778 0.5715)
						)
					)
					(width 0)
					(fill yes)
				)
			)
		)
		(pad "G" smd custom
			(at -0.98425 0.9525 270)
			(size 0.1905 0.1905)
			(layers "F.Cu" "F.Mask" "F.Paste")
			(net "P12V_MOST6_GATE")
			(options
				(clearance outline)
				(anchor circle)
			)
			(primitives
				(gr_poly
					(pts
						(arc
							(start -0.1778 0.5715)
							(mid -0.321484 0.511984)
							(end -0.381 0.3683)
						)
						(arc
							(start -0.381 -0.3683)
							(mid -0.321484 -0.511984)
							(end -0.1778 -0.5715)
						)
						(arc
							(start 0.1778 -0.5715)
							(mid 0.321484 -0.511984)
							(end 0.381 -0.3683)
						)
						(arc
							(start 0.381 0.3683)
							(mid 0.321484 0.511984)
							(end 0.1778 0.5715)
						)
					)
					(width 0)
					(fill yes)
				)
			)
		)
		(pad "S" smd custom
			(at 0.98425 0.9525 270)
			(size 0.1905 0.1905)
			(layers "F.Cu" "F.Mask" "F.Paste")
			(net "GND")
			(options
				(clearance outline)
				(anchor circle)
			)
			(primitives
				(gr_poly
					(pts
						(arc
							(start -0.1778 0.5715)
							(mid -0.321484 0.511984)
							(end -0.381 0.3683)
						)
						(arc
							(start -0.381 -0.3683)
							(mid -0.321484 -0.511984)
							(end -0.1778 -0.5715)
						)
						(arc
							(start 0.1778 -0.5715)
							(mid 0.321484 -0.511984)
							(end 0.381 -0.3683)
						)
						(arc
							(start 0.381 0.3683)
							(mid 0.321484 0.511984)
							(end 0.1778 0.5715)
						)
					)
					(width 0)
					(fill yes)
				)
			)
		)
	)
	(footprint ""
		(layer "F.Cu")
		(at 212.725 -454.66)
		(property "Reference" "R323"
			(at 0 0 0)
			(layer "F.SilkS")
			(hide yes)
			(effects
				(font
					(size 1.27 1.27)
				)
			)
		)
		(property "Value" "4K7R2J-2-GP"
			(at 0.064008 -3.993896 0)
			(unlocked yes)
			(layer "F.Fab")
			(hide yes)
			(effects
				(font
					(size 1.016 1.016)
					(thickness 0.1524)
				)
			)
		)
		(property "Device Type" "R402H16"
			(at 0.064008 -5.517896 0)
			(unlocked yes)
			(layer "F.Fab")
			(hide yes)
			(effects
				(font
					(size 1.016 1.016)
					(thickness 0.1524)
				)
			)
		)
		(duplicate_pad_numbers_are_jumpers no)
		(fp_line
			(start -0.508 -0.9398)
			(end -0.508 0.9398)
			(stroke
				(width 0.1524)
				(type default)
			)
			(layer "F.SilkS")
		)
		(fp_line
			(start 0.508 -0.9398)
			(end -0.508 -0.9398)
			(stroke
				(width 0.1524)
				(type default)
			)
			(layer "F.SilkS")
		)
		(fp_rect
			(start -0.508 0.9398)
			(end 0.508 -0.9398)
			(stroke
				(width 0)
				(type default)
			)
			(fill no)
			(layer "F.CrtYd")
		)
		(fp_rect
			(start -0.508 0.9398)
			(end 0.508 -0.9398)
			(stroke
				(width 0)
				(type default)
			)
			(fill no)
			(layer "F.Fab")
		)
		(pad "1" smd custom
			(at 0 -0.4445)
			(size 0.1397 0.1397)
			(layers "F.Cu" "F.Mask" "F.Paste")
			(net "I2C_B_TMP2_A2")
			(options
				(clearance outline)
				(anchor circle)
			)
			(primitives
				(gr_poly
					(pts
						(arc
							(start -0.1778 -0.2794)
							(mid -0.249642 -0.249642)
							(end -0.2794 -0.1778)
						)
						(arc
							(start -0.2794 0.1778)
							(mid -0.249642 0.249642)
							(end -0.1778 0.2794)
						)
						(arc
							(start 0.1778 0.2794)
							(mid 0.249642 0.249642)
							(end 0.2794 0.1778)
						)
						(arc
							(start 0.2794 -0.1778)
							(mid 0.249642 -0.249642)
							(end 0.1778 -0.2794)
						)
					)
					(width 0)
					(fill yes)
				)
			)
		)
		(pad "2" smd custom
			(at 0 0.4445)
			(size 0.1397 0.1397)
			(layers "F.Cu" "F.Mask" "F.Paste")
			(net "GND")
			(options
				(clearance outline)
				(anchor circle)
			)
			(primitives
				(gr_poly
					(pts
						(arc
							(start -0.1778 -0.2794)
							(mid -0.249642 -0.249642)
							(end -0.2794 -0.1778)
						)
						(arc
							(start -0.2794 0.1778)
							(mid -0.249642 0.249642)
							(end -0.1778 0.2794)
						)
						(arc
							(start 0.1778 0.2794)
							(mid 0.249642 0.249642)
							(end 0.2794 0.1778)
						)
						(arc
							(start 0.2794 -0.1778)
							(mid 0.249642 -0.249642)
							(end 0.1778 -0.2794)
						)
					)
					(width 0)
					(fill yes)
				)
			)
		)
	)
	(footprint ""
		(layer "F.Cu")
		(at 195.386706 -498.222778)
		(property "Reference" "R9760"
			(at 0 0 0)
			(layer "F.SilkS")
			(hide yes)
			(effects
				(font
					(size 1.27 1.27)
				)
			)
		)
		(property "Value" "4K7R2J-2-GP"
			(at 0.064008 -3.993896 0)
			(unlocked yes)
			(layer "F.Fab")
			(hide yes)
			(effects
				(font
					(size 1.016 1.016)
					(thickness 0.1524)
				)
			)
		)
		(property "Device Type" "R402H16"
			(at 0.064008 -5.517896 0)
			(unlocked yes)
			(layer "F.Fab")
			(hide yes)
			(effects
				(font
					(size 1.016 1.016)
					(thickness 0.1524)
				)
			)
		)
		(duplicate_pad_numbers_are_jumpers no)
		(fp_line
			(start -0.508 -0.9398)
			(end -0.508 0.9398)
			(stroke
				(width 0.1524)
				(type default)
			)
			(layer "F.SilkS")
		)
		(fp_line
			(start 0.508 -0.9398)
			(end -0.508 -0.9398)
			(stroke
				(width 0.1524)
				(type default)
			)
			(layer "F.SilkS")
		)
		(fp_rect
			(start -0.508 0.9398)
			(end 0.508 -0.9398)
			(stroke
				(width 0)
				(type default)
			)
			(fill no)
			(layer "F.CrtYd")
		)
		(fp_rect
			(start -0.508 0.9398)
			(end 0.508 -0.9398)
			(stroke
				(width 0)
				(type default)
			)
			(fill no)
			(layer "F.Fab")
		)
		(pad "1" smd custom
			(at 0 -0.4445)
			(size 0.1397 0.1397)
			(layers "F.Cu" "F.Mask" "F.Paste")
			(net "SSD0_PWREN")
			(options
				(clearance outline)
				(anchor circle)
			)
			(primitives
				(gr_poly
					(pts
						(arc
							(start -0.1778 -0.2794)
							(mid -0.249642 -0.249642)
							(end -0.2794 -0.1778)
						)
						(arc
							(start -0.2794 0.1778)
							(mid -0.249642 0.249642)
							(end -0.1778 0.2794)
						)
						(arc
							(start 0.1778 0.2794)
							(mid 0.249642 0.249642)
							(end 0.2794 0.1778)
						)
						(arc
							(start 0.2794 -0.1778)
							(mid 0.249642 -0.249642)
							(end 0.1778 -0.2794)
						)
					)
					(width 0)
					(fill yes)
				)
			)
		)
		(pad "2" smd custom
			(at 0 0.4445)
			(size 0.1397 0.1397)
			(layers "F.Cu" "F.Mask" "F.Paste")
			(net "GND")
			(options
				(clearance outline)
				(anchor circle)
			)
			(primitives
				(gr_poly
					(pts
						(arc
							(start -0.1778 -0.2794)
							(mid -0.249642 -0.249642)
							(end -0.2794 -0.1778)
						)
						(arc
							(start -0.2794 0.1778)
							(mid -0.249642 0.249642)
							(end -0.1778 0.2794)
						)
						(arc
							(start 0.1778 0.2794)
							(mid 0.249642 0.249642)
							(end 0.2794 0.1778)
						)
						(arc
							(start 0.2794 -0.1778)
							(mid 0.249642 -0.249642)
							(end 0.1778 -0.2794)
						)
					)
					(width 0)
					(fill yes)
				)
			)
		)
	)
	(footprint ""
		(layer "F.Cu")
		(at 228.510592 -37.834062 180)
		(property "Reference" "SR1130"
			(at 0 0 180)
			(layer "F.SilkS")
			(hide yes)
			(effects
				(font
					(size 1.27 1.27)
				)
			)
		)
		(property "Value" "4K7R2J-2-GP"
			(at 0.064008 -3.993896 180)
			(unlocked yes)
			(layer "F.Fab")
			(hide yes)
			(effects
				(font
					(size 1.016 1.016)
					(thickness 0.1524)
				)
			)
		)
		(property "Device Type" "R402H16"
			(at 0.064008 -5.517896 180)
			(unlocked yes)
			(layer "F.Fab")
			(hide yes)
			(effects
				(font
					(size 1.016 1.016)
					(thickness 0.1524)
				)
			)
		)
		(duplicate_pad_numbers_are_jumpers no)
		(fp_line
			(start 0.508 -0.9398)
			(end -0.508 -0.9398)
			(stroke
				(width 0.1524)
				(type default)
			)
			(layer "F.SilkS")
		)
		(fp_line
			(start -0.508 -0.9398)
			(end -0.508 0.9398)
			(stroke
				(width 0.1524)
				(type default)
			)
			(layer "F.SilkS")
		)
		(fp_rect
			(start -0.508 0.9398)
			(end 0.508 -0.9398)
			(stroke
				(width 0)
				(type default)
			)
			(fill no)
			(layer "F.CrtYd")
		)
		(fp_rect
			(start -0.508 0.9398)
			(end 0.508 -0.9398)
			(stroke
				(width 0)
				(type default)
			)
			(fill no)
			(layer "F.Fab")
		)
		(pad "1" smd custom
			(at 0 -0.4445 180)
			(size 0.1397 0.1397)
			(layers "F.Cu" "F.Mask" "F.Paste")
			(net "P3V3")
			(options
				(clearance outline)
				(anchor circle)
			)
			(primitives
				(gr_poly
					(pts
						(arc
							(start -0.1778 -0.2794)
							(mid -0.249642 -0.249642)
							(end -0.2794 -0.1778)
						)
						(arc
							(start -0.2794 0.1778)
							(mid -0.249642 0.249642)
							(end -0.1778 0.2794)
						)
						(arc
							(start 0.1778 0.2794)
							(mid 0.249642 0.249642)
							(end 0.2794 0.1778)
						)
						(arc
							(start 0.2794 -0.1778)
							(mid 0.249642 -0.249642)
							(end 0.1778 -0.2794)
						)
					)
					(width 0)
					(fill yes)
				)
			)
		)
		(pad "2" smd custom
			(at 0 0.4445 180)
			(size 0.1397 0.1397)
			(layers "F.Cu" "F.Mask" "F.Paste")
			(net "SSD_ACT_DR4")
			(options
				(clearance outline)
				(anchor circle)
			)
			(primitives
				(gr_poly
					(pts
						(arc
							(start -0.1778 -0.2794)
							(mid -0.249642 -0.249642)
							(end -0.2794 -0.1778)
						)
						(arc
							(start -0.2794 0.1778)
							(mid -0.249642 0.249642)
							(end -0.1778 0.2794)
						)
						(arc
							(start 0.1778 0.2794)
							(mid 0.249642 0.249642)
							(end 0.2794 0.1778)
						)
						(arc
							(start 0.2794 -0.1778)
							(mid 0.249642 -0.249642)
							(end 0.1778 -0.2794)
						)
					)
					(width 0)
					(fill yes)
				)
			)
		)
	)
	(footprint ""
		(layer "F.Cu")
		(at 96.774 -113.665 -90)
		(property "Reference" "C9370"
			(at 0 0 270)
			(layer "F.SilkS")
			(hide yes)
			(effects
				(font
					(size 1.27 1.27)
				)
			)
		)
		(property "Value" "SC1KP50V2KX-1GP"
			(at 1.1811 -2.7051 270)
			(unlocked yes)
			(layer "F.Fab")
			(hide yes)
			(effects
				(font
					(size 1.016 1.016)
					(thickness 0.1524)
				)
			)
		)
		(property "Device Type" "C402H22"
			(at 1.1811 -4.2291 270)
			(unlocked yes)
			(layer "F.Fab")
			(hide yes)
			(effects
				(font
					(size 1.016 1.016)
					(thickness 0.1524)
				)
			)
		)
		(duplicate_pad_numbers_are_jumpers no)
		(fp_rect
			(start -0.4318 0.9525)
			(end 0.4318 -0.9525)
			(stroke
				(width 0)
				(type default)
			)
			(fill no)
			(layer "F.CrtYd")
		)
		(fp_rect
			(start -0.4318 0.9525)
			(end 0.4318 -0.9525)
			(stroke
				(width 0)
				(type default)
			)
			(fill no)
			(layer "F.Fab")
		)
		(pad "1" smd custom
			(at 0 -0.4445 270)
			(size 0.1524 0.1524)
			(layers "F.Cu" "F.Mask" "F.Paste")
			(net "SSD8_CLK0_OE_R_N")
			(options
				(clearance outline)
				(anchor circle)
			)
			(primitives
				(gr_poly
					(pts
						(arc
							(start 0.3048 -0.2032)
							(mid 0.275042 -0.275042)
							(end 0.2032 -0.3048)
						)
						(arc
							(start -0.2032 -0.3048)
							(mid -0.275042 -0.275042)
							(end -0.3048 -0.2032)
						)
						(arc
							(start -0.3048 0.2032)
							(mid -0.275042 0.275042)
							(end -0.2032 0.3048)
						)
						(arc
							(start 0.2032 0.3048)
							(mid 0.275042 0.275042)
							(end 0.3048 0.2032)
						)
					)
					(width 0)
					(fill yes)
				)
			)
		)
		(pad "2" smd custom
			(at 0 0.4445 270)
			(size 0.1524 0.1524)
			(layers "F.Cu" "F.Mask" "F.Paste")
			(net "GND")
			(options
				(clearance outline)
				(anchor circle)
			)
			(primitives
				(gr_poly
					(pts
						(arc
							(start 0.3048 -0.2032)
							(mid 0.275042 -0.275042)
							(end 0.2032 -0.3048)
						)
						(arc
							(start -0.2032 -0.3048)
							(mid -0.275042 -0.275042)
							(end -0.3048 -0.2032)
						)
						(arc
							(start -0.3048 0.2032)
							(mid -0.275042 0.275042)
							(end -0.2032 0.3048)
						)
						(arc
							(start 0.2032 0.3048)
							(mid 0.275042 0.275042)
							(end 0.3048 0.2032)
						)
					)
					(width 0)
					(fill yes)
				)
			)
		)
	)
)
